(kicad_pcb
	(version 20260206)
	(generator "pcbnew")
	(generator_version "10.0")
	(general
		(thickness 1.6)
		(legacy_teardrops no)
	)
	(paper "A4")
	(title_block
		(title "panther-plus-userver — 13130-1b_20150205.brd")
		(comment 1 "Honey Badger (Wiwynn) / footprint 624 of 1509 (DIMM4), pads 93-99 of 210")
	)
	(layers
		(0 "F.Cu" signal "TOP")
		(4 "In1.Cu" signal "L2")
		(6 "In2.Cu" signal "L3")
		(8 "In3.Cu" signal "L4")
		(10 "In4.Cu" signal "L5")
		(12 "In5.Cu" signal "L6")
		(14 "In6.Cu" signal "L7")
		(16 "In7.Cu" signal "L8")
		(18 "In8.Cu" signal "L9")
		(20 "In9.Cu" signal "L10")
		(22 "In10.Cu" signal "L11")
		(2 "B.Cu" signal "BOTTOM")
		(9 "F.Adhes" user "F.Adhesive")
		(11 "B.Adhes" user "B.Adhesive")
		(13 "F.Paste" user "Package Geometry/Pastemask Top")
		(15 "B.Paste" user "Package Geometry/Pastemask Bottom")
		(5 "F.SilkS" user "Ref Des/Silkscreen Top")
		(7 "B.SilkS" user "Ref Des/Silkscreen Bottom")
		(1 "F.Mask" user "Board Geometry/Soldermask Top")
		(3 "B.Mask" user "Board Geometry/Soldermask Bottom")
		(17 "Dwgs.User" user "User.Drawings")
		(19 "Cmts.User" user "User.Comments")
		(21 "Eco1.User" user "User.Eco1")
		(23 "Eco2.User" user "User.Eco2")
		(25 "Edge.Cuts" user "Board Geometry/Outline")
		(27 "Margin" user)
		(31 "F.CrtYd" user "Package Geometry/Place Bound Top")
		(29 "B.CrtYd" user "Package Geometry/Place Bound Bottom")
		(35 "F.Fab" user "Ref Des/Assembly Top")
		(33 "B.Fab" user "Ref Des/Assembly Bottom")
	)
	(footprint ""
		(layer "F.Cu")
		(at 159.999934 -5.790692)
		(property "Reference" "DIMM4"
			(at 0 0 0)
			(layer "F.SilkS")
			(hide yes)
			(effects
				(font
					(size 1.27 1.27)
				)
			)
		)
		(property "Value" "DDR3-204P-174-COLAY-1-GP"
			(at -40.682164 -17.468088 0)
			(unlocked yes)
			(layer "F.Fab")
			(hide yes)
			(effects
				(font
					(size 1.016 1.016)
					(thickness 0.1524)
				)
			)
		)
		(property "Device Type" "AS0A626-H8SN-7H-COLAY-1"
			(at -40.682164 -18.992088 0)
			(unlocked yes)
			(layer "F.Fab")
			(hide yes)
			(effects
				(font
					(size 1.016 1.016)
					(thickness 0.1524)
				)
			)
		)
		(duplicate_pad_numbers_are_jumpers no)
		(pad "91" smd custom
			(at -2.249932 4.106672)
			(size 0.1143 0.1143)
			(layers "F.Cu" "F.Mask" "F.Paste")
			(net "M_B_BS2")
			(options
				(clearance outline)
				(anchor circle)
			)
			(primitives
				(gr_poly
					(pts
						(xy 0 0.9017) (xy -0.03175 0.89916) (xy -0.0635 0.889) (xy -0.09144 0.87376) (xy -0.11684 0.85344)
						(xy -0.13716 0.82804) (xy -0.1524 0.8001) (xy -0.16256 0.76835) (xy -0.1651 0.7366) (xy -0.1651 0.11938)
						(xy -0.17272 0.11176) (xy -0.19812 0.0762) (xy -0.2032 0.06604) (xy -0.20701 0.05715) (xy -0.21209 0.04699)
						(xy -0.2159 0.03683) (xy -0.21844 0.02667) (xy -0.22225 0.01524) (xy -0.22352 0.00508) (xy -0.22606 -0.00508)
						(xy -0.22733 -0.01651) (xy -0.22733 -0.02667) (xy -0.2286 -0.0381) (xy -0.22733 -0.04953) (xy -0.22733 -0.05969)
						(xy -0.22606 -0.07112) (xy -0.22352 -0.08128) (xy -0.22225 -0.09144) (xy -0.21844 -0.10287) (xy -0.2159 -0.11303)
						(xy -0.21209 -0.12319) (xy -0.20701 -0.13335) (xy -0.2032 -0.14224) (xy -0.19812 -0.1524) (xy -0.17272 -0.18796)
						(xy -0.1651 -0.19558) (xy -0.1651 -0.7366) (xy -0.16256 -0.76835) (xy -0.1524 -0.8001) (xy -0.13716 -0.82804)
						(xy -0.11684 -0.85344) (xy -0.09144 -0.87376) (xy -0.0635 -0.889) (xy -0.03175 -0.89916) (xy 0 -0.9017)
						(xy 0.03175 -0.89916) (xy 0.0635 -0.889) (xy 0.09144 -0.87376) (xy 0.11684 -0.85344) (xy 0.13716 -0.82804)
						(xy 0.1524 -0.8001) (xy 0.16256 -0.76835) (xy 0.1651 -0.7366) (xy 0.1651 -0.19685) (xy 0.17272 -0.18923)
						(xy 0.17907 -0.18034) (xy 0.18669 -0.17145) (xy 0.19177 -0.16256) (xy 0.19812 -0.15367) (xy 0.20828 -0.13335)
						(xy 0.21971 -0.10287) (xy 0.22225 -0.09271) (xy 0.22479 -0.08128) (xy 0.22606 -0.07112) (xy 0.2286 -0.05969)
						(xy 0.2286 -0.01651) (xy 0.22606 -0.00508) (xy 0.22479 0.00508) (xy 0.22225 0.01651) (xy 0.21971 0.02667)
						(xy 0.20828 0.05715) (xy 0.19812 0.07747) (xy 0.19177 0.08636) (xy 0.18669 0.09525) (xy 0.17907 0.10414)
						(xy 0.17272 0.11303) (xy 0.1651 0.12065) (xy 0.1651 0.7366) (xy 0.16256 0.76835) (xy 0.1524 0.8001)
						(xy 0.13716 0.82804) (xy 0.11684 0.85344) (xy 0.09144 0.87376) (xy 0.0635 0.889) (xy 0.03175 0.89916)
					)
					(width 0)
					(fill yes)
				)
			)
		)
		(pad "92" smd custom
			(at -1.949958 -4.106672)
			(size 0.1143 0.1143)
			(layers "F.Cu" "F.Mask" "F.Paste")
			(net "M_B_MA9")
			(options
				(clearance outline)
				(anchor circle)
			)
			(primitives
				(gr_poly
					(pts
						(xy 0 0.9017) (xy -0.03175 0.89916) (xy -0.0635 0.889) (xy -0.09144 0.87376) (xy -0.11684 0.85344)
						(xy -0.13716 0.82804) (xy -0.1524 0.8001) (xy -0.16256 0.76835) (xy -0.1651 0.7366) (xy -0.1651 0.19685)
						(xy -0.17272 0.18923) (xy -0.17907 0.18034) (xy -0.18669 0.17145) (xy -0.19177 0.16256) (xy -0.19812 0.15367)
						(xy -0.20828 0.13335) (xy -0.21971 0.10287) (xy -0.22225 0.09271) (xy -0.22479 0.08128) (xy -0.22606 0.07112)
						(xy -0.2286 0.05969) (xy -0.2286 0.01651) (xy -0.22606 0.00508) (xy -0.22479 -0.00508) (xy -0.22225 -0.01651)
						(xy -0.21971 -0.02667) (xy -0.20828 -0.05715) (xy -0.19812 -0.07747) (xy -0.19177 -0.08636) (xy -0.18669 -0.09525)
						(xy -0.17907 -0.10414) (xy -0.17272 -0.11303) (xy -0.1651 -0.12065) (xy -0.1651 -0.7366) (xy -0.16256 -0.76835)
						(xy -0.1524 -0.8001) (xy -0.13716 -0.82804) (xy -0.11684 -0.85344) (xy -0.09144 -0.87376) (xy -0.0635 -0.889)
						(xy -0.03175 -0.89916) (xy 0 -0.9017) (xy 0.03175 -0.89916) (xy 0.0635 -0.889) (xy 0.09144 -0.87376)
						(xy 0.11684 -0.85344) (xy 0.13716 -0.82804) (xy 0.1524 -0.8001) (xy 0.16256 -0.76835) (xy 0.1651 -0.7366)
						(xy 0.1651 -0.11938) (xy 0.17272 -0.11176) (xy 0.19812 -0.0762) (xy 0.2032 -0.06604) (xy 0.20701 -0.05715)
						(xy 0.21209 -0.04699) (xy 0.2159 -0.03683) (xy 0.21844 -0.02667) (xy 0.22225 -0.01524) (xy 0.22352 -0.00508)
						(xy 0.22606 0.00508) (xy 0.22733 0.01651) (xy 0.22733 0.02667) (xy 0.2286 0.0381) (xy 0.22733 0.04953)
						(xy 0.22733 0.05969) (xy 0.22606 0.07112) (xy 0.22352 0.08128) (xy 0.22225 0.09144) (xy 0.21844 0.10287)
						(xy 0.2159 0.11303) (xy 0.21209 0.12319) (xy 0.20701 0.13335) (xy 0.2032 0.14224) (xy 0.19812 0.1524)
						(xy 0.17272 0.18796) (xy 0.1651 0.19558) (xy 0.1651 0.7366) (xy 0.16256 0.76835) (xy 0.1524 0.8001)
						(xy 0.13716 0.82804) (xy 0.11684 0.85344) (xy 0.09144 0.87376) (xy 0.0635 0.889) (xy 0.03175 0.89916)
					)
					(width 0)
					(fill yes)
				)
			)
		)
		(pad "93" smd custom
			(at -1.649984 4.106672)
			(size 0.1143 0.1143)
			(layers "F.Cu" "F.Mask" "F.Paste")
			(net "PV_VDDR")
			(options
				(clearance outline)
				(anchor circle)
			)
			(primitives
				(gr_poly
					(pts
						(xy 0 0.9017) (xy -0.03175 0.89916) (xy -0.0635 0.889) (xy -0.09144 0.87376) (xy -0.11684 0.85344)
						(xy -0.13716 0.82804) (xy -0.1524 0.8001) (xy -0.16256 0.76835) (xy -0.1651 0.7366) (xy -0.1651 -0.13462)
						(xy -0.17272 -0.14224) (xy -0.19812 -0.1778) (xy -0.2032 -0.18796) (xy -0.20701 -0.19685) (xy -0.21209 -0.20701)
						(xy -0.2159 -0.21717) (xy -0.21844 -0.22733) (xy -0.22225 -0.23876) (xy -0.22352 -0.24892) (xy -0.22606 -0.25908)
						(xy -0.22733 -0.27051) (xy -0.22733 -0.28067) (xy -0.2286 -0.2921) (xy -0.22733 -0.30353) (xy -0.22733 -0.31369)
						(xy -0.22606 -0.32512) (xy -0.22352 -0.33528) (xy -0.22225 -0.34544) (xy -0.21844 -0.35687) (xy -0.2159 -0.36703)
						(xy -0.21209 -0.37719) (xy -0.20701 -0.38735) (xy -0.2032 -0.39624) (xy -0.19812 -0.4064) (xy -0.17272 -0.44196)
						(xy -0.1651 -0.44958) (xy -0.1651 -0.7366) (xy -0.16256 -0.76835) (xy -0.1524 -0.8001) (xy -0.13716 -0.82804)
						(xy -0.11684 -0.85344) (xy -0.09144 -0.87376) (xy -0.0635 -0.889) (xy -0.03175 -0.89916) (xy 0 -0.9017)
						(xy 0.03175 -0.89916) (xy 0.0635 -0.889) (xy 0.09144 -0.87376) (xy 0.11684 -0.85344) (xy 0.13716 -0.82804)
						(xy 0.1524 -0.8001) (xy 0.16256 -0.76835) (xy 0.1651 -0.7366) (xy 0.1651 -0.44958) (xy 0.17272 -0.44196)
						(xy 0.19812 -0.4064) (xy 0.2032 -0.39624) (xy 0.20701 -0.38735) (xy 0.21209 -0.37719) (xy 0.2159 -0.36703)
						(xy 0.21844 -0.35687) (xy 0.22225 -0.34544) (xy 0.22352 -0.33528) (xy 0.22606 -0.32512) (xy 0.22733 -0.31369)
						(xy 0.22733 -0.30353) (xy 0.2286 -0.2921) (xy 0.22733 -0.28067) (xy 0.22733 -0.27051) (xy 0.22606 -0.25908)
						(xy 0.22352 -0.24892) (xy 0.22225 -0.23876) (xy 0.21844 -0.22733) (xy 0.2159 -0.21717) (xy 0.21209 -0.20701)
						(xy 0.20701 -0.19685) (xy 0.2032 -0.18796) (xy 0.19812 -0.1778) (xy 0.17272 -0.14224) (xy 0.1651 -0.13462)
						(xy 0.1651 0.7366) (xy 0.16256 0.76835) (xy 0.1524 0.8001) (xy 0.13716 0.82804) (xy 0.11684 0.85344)
						(xy 0.09144 0.87376) (xy 0.0635 0.889) (xy 0.03175 0.89916)
					)
					(width 0)
					(fill yes)
				)
			)
		)
		(pad "94" smd custom
			(at -1.35001 -4.106672)
			(size 0.1143 0.1143)
			(layers "F.Cu" "F.Mask" "F.Paste")
			(net "PV_VDDR")
			(options
				(clearance outline)
				(anchor circle)
			)
			(primitives
				(gr_poly
					(pts
						(xy 0 0.9017) (xy -0.03175 0.89916) (xy -0.0635 0.889) (xy -0.09144 0.87376) (xy -0.11684 0.85344)
						(xy -0.13716 0.82804) (xy -0.1524 0.8001) (xy -0.16256 0.76835) (xy -0.1651 0.7366) (xy -0.1651 0.44958)
						(xy -0.17272 0.44196) (xy -0.19812 0.4064) (xy -0.2032 0.39624) (xy -0.20701 0.38735) (xy -0.21209 0.37719)
						(xy -0.2159 0.36703) (xy -0.21844 0.35687) (xy -0.22225 0.34544) (xy -0.22352 0.33528) (xy -0.22606 0.32512)
						(xy -0.22733 0.31369) (xy -0.22733 0.30353) (xy -0.2286 0.2921) (xy -0.22733 0.28067) (xy -0.22733 0.27051)
						(xy -0.22606 0.25908) (xy -0.22352 0.24892) (xy -0.22225 0.23876) (xy -0.21844 0.22733) (xy -0.2159 0.21717)
						(xy -0.21209 0.20701) (xy -0.20701 0.19685) (xy -0.2032 0.18796) (xy -0.19812 0.1778) (xy -0.17272 0.14224)
						(xy -0.1651 0.13462) (xy -0.1651 -0.7366) (xy -0.16256 -0.76835) (xy -0.1524 -0.8001) (xy -0.13716 -0.82804)
						(xy -0.11684 -0.85344) (xy -0.09144 -0.87376) (xy -0.0635 -0.889) (xy -0.03175 -0.89916) (xy 0 -0.9017)
						(xy 0.03175 -0.89916) (xy 0.0635 -0.889) (xy 0.09144 -0.87376) (xy 0.11684 -0.85344) (xy 0.13716 -0.82804)
						(xy 0.1524 -0.8001) (xy 0.16256 -0.76835) (xy 0.1651 -0.7366) (xy 0.1651 0.13462) (xy 0.17272 0.14224)
						(xy 0.19812 0.1778) (xy 0.2032 0.18796) (xy 0.20701 0.19685) (xy 0.21209 0.20701) (xy 0.2159 0.21717)
						(xy 0.21844 0.22733) (xy 0.22225 0.23876) (xy 0.22352 0.24892) (xy 0.22606 0.25908) (xy 0.22733 0.27051)
						(xy 0.22733 0.28067) (xy 0.2286 0.2921) (xy 0.22733 0.30353) (xy 0.22733 0.31369) (xy 0.22606 0.32512)
						(xy 0.22352 0.33528) (xy 0.22225 0.34544) (xy 0.21844 0.35687) (xy 0.2159 0.36703) (xy 0.21209 0.37719)
						(xy 0.20701 0.38735) (xy 0.2032 0.39624) (xy 0.19812 0.4064) (xy 0.17272 0.44196) (xy 0.1651 0.44958)
						(xy 0.1651 0.7366) (xy 0.16256 0.76835) (xy 0.1524 0.8001) (xy 0.13716 0.82804) (xy 0.11684 0.85344)
						(xy 0.09144 0.87376) (xy 0.0635 0.889) (xy 0.03175 0.89916)
					)
					(width 0)
					(fill yes)
				)
			)
		)
		(pad "95" smd custom
			(at -1.050036 4.106672)
			(size 0.1143 0.1143)
			(layers "F.Cu" "F.Mask" "F.Paste")
			(net "M_B_MA12")
			(options
				(clearance outline)
				(anchor circle)
			)
			(primitives
				(gr_poly
					(pts
						(xy 0 0.9017) (xy -0.03175 0.89916) (xy -0.0635 0.889) (xy -0.09144 0.87376) (xy -0.11684 0.85344)
						(xy -0.13716 0.82804) (xy -0.1524 0.8001) (xy -0.16256 0.76835) (xy -0.1651 0.7366) (xy -0.1651 0.11938)
						(xy -0.17272 0.11176) (xy -0.19812 0.0762) (xy -0.2032 0.06604) (xy -0.20701 0.05715) (xy -0.21209 0.04699)
						(xy -0.2159 0.03683) (xy -0.21844 0.02667) (xy -0.22225 0.01524) (xy -0.22352 0.00508) (xy -0.22606 -0.00508)
						(xy -0.22733 -0.01651) (xy -0.22733 -0.02667) (xy -0.2286 -0.0381) (xy -0.22733 -0.04953) (xy -0.22733 -0.05969)
						(xy -0.22606 -0.07112) (xy -0.22352 -0.08128) (xy -0.22225 -0.09144) (xy -0.21844 -0.10287) (xy -0.2159 -0.11303)
						(xy -0.21209 -0.12319) (xy -0.20701 -0.13335) (xy -0.2032 -0.14224) (xy -0.19812 -0.1524) (xy -0.17272 -0.18796)
						(xy -0.1651 -0.19558) (xy -0.1651 -0.7366) (xy -0.16256 -0.76835) (xy -0.1524 -0.8001) (xy -0.13716 -0.82804)
						(xy -0.11684 -0.85344) (xy -0.09144 -0.87376) (xy -0.0635 -0.889) (xy -0.03175 -0.89916) (xy 0 -0.9017)
						(xy 0.03175 -0.89916) (xy 0.0635 -0.889) (xy 0.09144 -0.87376) (xy 0.11684 -0.85344) (xy 0.13716 -0.82804)
						(xy 0.1524 -0.8001) (xy 0.16256 -0.76835) (xy 0.1651 -0.7366) (xy 0.1651 -0.19685) (xy 0.17272 -0.18923)
						(xy 0.17907 -0.18034) (xy 0.18669 -0.17145) (xy 0.19177 -0.16256) (xy 0.19812 -0.15367) (xy 0.20828 -0.13335)
						(xy 0.21971 -0.10287) (xy 0.22225 -0.09271) (xy 0.22479 -0.08128) (xy 0.22606 -0.07112) (xy 0.2286 -0.05969)
						(xy 0.2286 -0.01651) (xy 0.22606 -0.00508) (xy 0.22479 0.00508) (xy 0.22225 0.01651) (xy 0.21971 0.02667)
						(xy 0.20828 0.05715) (xy 0.19812 0.07747) (xy 0.19177 0.08636) (xy 0.18669 0.09525) (xy 0.17907 0.10414)
						(xy 0.17272 0.11303) (xy 0.1651 0.12065) (xy 0.1651 0.7366) (xy 0.16256 0.76835) (xy 0.1524 0.8001)
						(xy 0.13716 0.82804) (xy 0.11684 0.85344) (xy 0.09144 0.87376) (xy 0.0635 0.889) (xy 0.03175 0.89916)
					)
					(width 0)
					(fill yes)
				)
			)
		)
		(pad "96" smd custom
			(at -0.750062 -4.106672)
			(size 0.1143 0.1143)
			(layers "F.Cu" "F.Mask" "F.Paste")
			(net "M_B_MA11")
			(options
				(clearance outline)
				(anchor circle)
			)
			(primitives
				(gr_poly
					(pts
						(xy 0 0.9017) (xy -0.03175 0.89916) (xy -0.0635 0.889) (xy -0.09144 0.87376) (xy -0.11684 0.85344)
						(xy -0.13716 0.82804) (xy -0.1524 0.8001) (xy -0.16256 0.76835) (xy -0.1651 0.7366) (xy -0.1651 0.19685)
						(xy -0.17272 0.18923) (xy -0.17907 0.18034) (xy -0.18669 0.17145) (xy -0.19177 0.16256) (xy -0.19812 0.15367)
						(xy -0.20828 0.13335) (xy -0.21971 0.10287) (xy -0.22225 0.09271) (xy -0.22479 0.08128) (xy -0.22606 0.07112)
						(xy -0.2286 0.05969) (xy -0.2286 0.01651) (xy -0.22606 0.00508) (xy -0.22479 -0.00508) (xy -0.22225 -0.01651)
						(xy -0.21971 -0.02667) (xy -0.20828 -0.05715) (xy -0.19812 -0.07747) (xy -0.19177 -0.08636) (xy -0.18669 -0.09525)
						(xy -0.17907 -0.10414) (xy -0.17272 -0.11303) (xy -0.1651 -0.12065) (xy -0.1651 -0.7366) (xy -0.16256 -0.76835)
						(xy -0.1524 -0.8001) (xy -0.13716 -0.82804) (xy -0.11684 -0.85344) (xy -0.09144 -0.87376) (xy -0.0635 -0.889)
						(xy -0.03175 -0.89916) (xy 0 -0.9017) (xy 0.03175 -0.89916) (xy 0.0635 -0.889) (xy 0.09144 -0.87376)
						(xy 0.11684 -0.85344) (xy 0.13716 -0.82804) (xy 0.1524 -0.8001) (xy 0.16256 -0.76835) (xy 0.1651 -0.7366)
						(xy 0.1651 -0.11938) (xy 0.17272 -0.11176) (xy 0.19812 -0.0762) (xy 0.2032 -0.06604) (xy 0.20701 -0.05715)
						(xy 0.21209 -0.04699) (xy 0.2159 -0.03683) (xy 0.21844 -0.02667) (xy 0.22225 -0.01524) (xy 0.22352 -0.00508)
						(xy 0.22606 0.00508) (xy 0.22733 0.01651) (xy 0.22733 0.02667) (xy 0.2286 0.0381) (xy 0.22733 0.04953)
						(xy 0.22733 0.05969) (xy 0.22606 0.07112) (xy 0.22352 0.08128) (xy 0.22225 0.09144) (xy 0.21844 0.10287)
						(xy 0.2159 0.11303) (xy 0.21209 0.12319) (xy 0.20701 0.13335) (xy 0.2032 0.14224) (xy 0.19812 0.1524)
						(xy 0.17272 0.18796) (xy 0.1651 0.19558) (xy 0.1651 0.7366) (xy 0.16256 0.76835) (xy 0.1524 0.8001)
						(xy 0.13716 0.82804) (xy 0.11684 0.85344) (xy 0.09144 0.87376) (xy 0.0635 0.889) (xy 0.03175 0.89916)
					)
					(width 0)
					(fill yes)
				)
			)
		)
		(pad "97" smd custom
			(at -0.450088 4.106672)
			(size 0.1143 0.1143)
			(layers "F.Cu" "F.Mask" "F.Paste")
			(net "M_B_MA8")
			(options
				(clearance outline)
				(anchor circle)
			)
			(primitives
				(gr_poly
					(pts
						(xy 0 0.9017) (xy -0.03175 0.89916) (xy -0.0635 0.889) (xy -0.09144 0.87376) (xy -0.11684 0.85344)
						(xy -0.13716 0.82804) (xy -0.1524 0.8001) (xy -0.16256 0.76835) (xy -0.1651 0.7366) (xy -0.1651 -0.13462)
						(xy -0.17272 -0.14224) (xy -0.19812 -0.1778) (xy -0.2032 -0.18796) (xy -0.20701 -0.19685) (xy -0.21209 -0.20701)
						(xy -0.2159 -0.21717) (xy -0.21844 -0.22733) (xy -0.22225 -0.23876) (xy -0.22352 -0.24892) (xy -0.22606 -0.25908)
						(xy -0.22733 -0.27051) (xy -0.22733 -0.28067) (xy -0.2286 -0.2921) (xy -0.22733 -0.30353) (xy -0.22733 -0.31369)
						(xy -0.22606 -0.32512) (xy -0.22352 -0.33528) (xy -0.22225 -0.34544) (xy -0.21844 -0.35687) (xy -0.2159 -0.36703)
						(xy -0.21209 -0.37719) (xy -0.20701 -0.38735) (xy -0.2032 -0.39624) (xy -0.19812 -0.4064) (xy -0.17272 -0.44196)
						(xy -0.1651 -0.44958) (xy -0.1651 -0.7366) (xy -0.16256 -0.76835) (xy -0.1524 -0.8001) (xy -0.13716 -0.82804)
						(xy -0.11684 -0.85344) (xy -0.09144 -0.87376) (xy -0.0635 -0.889) (xy -0.03175 -0.89916) (xy 0 -0.9017)
						(xy 0.03175 -0.89916) (xy 0.0635 -0.889) (xy 0.09144 -0.87376) (xy 0.11684 -0.85344) (xy 0.13716 -0.82804)
						(xy 0.1524 -0.8001) (xy 0.16256 -0.76835) (xy 0.1651 -0.7366) (xy 0.1651 -0.44958) (xy 0.17272 -0.44196)
						(xy 0.19812 -0.4064) (xy 0.2032 -0.39624) (xy 0.20701 -0.38735) (xy 0.21209 -0.37719) (xy 0.2159 -0.36703)
						(xy 0.21844 -0.35687) (xy 0.22225 -0.34544) (xy 0.22352 -0.33528) (xy 0.22606 -0.32512) (xy 0.22733 -0.31369)
						(xy 0.22733 -0.30353) (xy 0.2286 -0.2921) (xy 0.22733 -0.28067) (xy 0.22733 -0.27051) (xy 0.22606 -0.25908)
						(xy 0.22352 -0.24892) (xy 0.22225 -0.23876) (xy 0.21844 -0.22733) (xy 0.2159 -0.21717) (xy 0.21209 -0.20701)
						(xy 0.20701 -0.19685) (xy 0.2032 -0.18796) (xy 0.19812 -0.1778) (xy 0.17272 -0.14224) (xy 0.1651 -0.13462)
						(xy 0.1651 0.7366) (xy 0.16256 0.76835) (xy 0.1524 0.8001) (xy 0.13716 0.82804) (xy 0.11684 0.85344)
						(xy 0.09144 0.87376) (xy 0.0635 0.889) (xy 0.03175 0.89916)
					)
					(width 0)
					(fill yes)
				)
			)
		)
	)
)
